# BASEBOARD_FAB2 (Tioga Pass) — schematic netlist excerpt (pin names and nets, part order shuffled) for the footprints in the layout excerpt that follows; sources: Cadence DE-HDL packaged netlist, KiCad conversion of Wiwynn_Tioga_Pass_MB.brd

C3N14  CAPP  470UF 2.5V 20% ALUM  pkg 3018  page 194 : A = PVCCIOMCP_CPU0 ; B = GND
C5P23  CAP  47UF 4V 20% X6S  pkg 0805  page 42 : A = PVCCIN_CPU0 ; B = GND
R2R9  RES  200.0 1% CHIP  pkg 0402  page 157 : A = FP_NMI_BTN_OUT_R_N ; B = FP_NMI_BTN_OUT_N

(kicad_pcb
	(version 20260206)
	(generator "pcbnew")
	(generator_version "10.0")
	(general
		(thickness 1.6)
		(legacy_teardrops no)
	)
	(paper "A4")
	(title_block
		(title "Wiwynn_Tioga_Pass_MB.brd")
		(comment 1 "Tioga Pass / footprints 4351-4353 of 4770")
	)
	(layers
		(0 "F.Cu" signal "TOP")
		(4 "In1.Cu" signal "L2GND")
		(6 "In2.Cu" signal "L3")
		(8 "In3.Cu" signal "L4GND")
		(10 "In4.Cu" signal "L5")
		(12 "In5.Cu" signal "L6GND")
		(14 "In6.Cu" signal "L7VCC")
		(16 "In7.Cu" signal "L8VCC")
		(18 "In8.Cu" signal "L9GND")
		(20 "In9.Cu" signal "L10")
		(22 "In10.Cu" signal "L11GND")
		(24 "In11.Cu" signal "L12")
		(26 "In12.Cu" signal "L13GND")
		(2 "B.Cu" signal "BOTTOM")
		(9 "F.Adhes" user "F.Adhesive")
		(11 "B.Adhes" user "B.Adhesive")
		(13 "F.Paste" user "Package Geometry/Pastemask Top")
		(15 "B.Paste" user "Package Geometry/Pastemask Bottom")
		(5 "F.SilkS" user "Ref Des/Silkscreen Top")
		(7 "B.SilkS" user "Ref Des/Silkscreen Bottom")
		(1 "F.Mask" user "Board Geometry/Soldermask Top")
		(3 "B.Mask" user "Board Geometry/Soldermask Bottom")
		(17 "Dwgs.User" user "User.Drawings")
		(19 "Cmts.User" user "User.Comments")
		(21 "Eco1.User" user "User.Eco1")
		(23 "Eco2.User" user "User.Eco2")
		(25 "Edge.Cuts" user "Board Geometry/Outline")
		(27 "Margin" user)
		(31 "F.CrtYd" user "Package Geometry/Place Bound Top")
		(29 "B.CrtYd" user "Package Geometry/Place Bound Bottom")
		(35 "F.Fab" user "Ref Des/Assembly Top")
		(33 "B.Fab" user "Ref Des/Assembly Bottom")
	)
	(footprint ""
		(layer "B.Cu")
		(at 349.4024 -109.474 -90)
		(property "Reference" "C3N14"
			(at 3.58267 0.4064 0)
			(unlocked yes)
			(layer "B.SilkS")
			(effects
				(font
					(size 0.7874 0.5842)
					(thickness 0.1524)
				)
				(justify mirror)
			)
		)
		(property "Value" ""
			(at 0 0 90)
			(layer "B.Fab")
			(effects
				(font
					(size 1.27 1.27)
				)
				(justify mirror)
			)
		)
		(duplicate_pad_numbers_are_jumpers no)
		(fp_line
			(start -2.286 7.366)
			(end -1.600708 7.366)
			(stroke
				(width 0.1524)
				(type default)
			)
			(layer "B.SilkS")
		)
		(fp_line
			(start -2.286 7.366)
			(end -2.286 1.63195)
			(stroke
				(width 0.1524)
				(type default)
			)
			(layer "B.SilkS")
		)
		(fp_line
			(start 2.286 7.366)
			(end 1.60147 7.366)
			(stroke
				(width 0.1524)
				(type default)
			)
			(layer "B.SilkS")
		)
		(fp_line
			(start 2.286 7.366)
			(end 2.286 1.632712)
			(stroke
				(width 0.1524)
				(type default)
			)
			(layer "B.SilkS")
		)
		(fp_line
			(start -2.504948 1.633728)
			(end -1.6002 1.633728)
			(stroke
				(width 0.1524)
				(type default)
			)
			(layer "B.SilkS")
		)
		(fp_line
			(start 2.563114 1.633728)
			(end 1.6002 1.633728)
			(stroke
				(width 0.1524)
				(type default)
			)
			(layer "B.SilkS")
		)
		(fp_line
			(start -2.504948 -1.616456)
			(end -2.504948 1.633728)
			(stroke
				(width 0.1524)
				(type default)
			)
			(layer "B.SilkS")
		)
		(fp_line
			(start -1.6002 -1.616456)
			(end -2.504948 -1.616456)
			(stroke
				(width 0.1524)
				(type default)
			)
			(layer "B.SilkS")
		)
		(fp_line
			(start 1.6002 -1.616456)
			(end 2.563114 -1.616456)
			(stroke
				(width 0.1524)
				(type default)
			)
			(layer "B.SilkS")
		)
		(fp_line
			(start 2.563114 -1.616456)
			(end 2.563114 1.633728)
			(stroke
				(width 0.1524)
				(type default)
			)
			(layer "B.SilkS")
		)
		(fp_rect
			(start 2.286 7.366)
			(end -2.286 -0.254)
			(stroke
				(width 0)
				(type default)
			)
			(fill no)
			(layer "B.CrtYd")
		)
		(fp_line
			(start -2.286 7.366)
			(end 2.286 7.366)
			(stroke
				(width 0.1)
				(type default)
			)
			(layer "B.Fab")
		)
		(fp_line
			(start 2.286 7.366)
			(end 2.286 -0.254)
			(stroke
				(width 0.1)
				(type default)
			)
			(layer "B.Fab")
		)
		(fp_line
			(start -2.286 -0.254)
			(end -2.286 7.366)
			(stroke
				(width 0.1)
				(type default)
			)
			(layer "B.Fab")
		)
		(fp_line
			(start 2.286 -0.254)
			(end -2.286 -0.254)
			(stroke
				(width 0.1)
				(type default)
			)
			(layer "B.Fab")
		)
		(pad "1" smd rect
			(at 0 0 90)
			(size 2.54 3.048)
			(layers "B.Cu" "B.Mask" "B.Paste")
			(net "PVCCIOMCP_CPU0")
		)
		(pad "2" smd rect
			(at 0 7.112 90)
			(size 2.54 3.048)
			(layers "B.Cu" "B.Mask" "B.Paste")
			(net "GND")
		)
	)
	(footprint ""
		(layer "B.Cu")
		(at 411.791658 -11.877802 -90)
		(property "Reference" "R2R9"
			(at 0 0 90)
			(layer "B.SilkS")
			(hide yes)
			(effects
				(font
					(size 1.27 1.27)
				)
				(justify mirror)
			)
		)
		(property "Value" ""
			(at 0 0 90)
			(layer "B.Fab")
			(effects
				(font
					(size 1.27 1.27)
				)
				(justify mirror)
			)
		)
		(duplicate_pad_numbers_are_jumpers no)
		(fp_poly
			(pts
				(xy 0.2794 -0.1016) (xy -0.2794 -0.1016) (xy -0.2794 0.9906) (xy 0.2794 0.9906)
			)
			(stroke
				(width 0)
				(type default)
			)
			(fill no)
			(layer "B.CrtYd")
		)
		(fp_line
			(start -0.2794 0.9906)
			(end -0.2794 -0.1016)
			(stroke
				(width 0.1)
				(type default)
			)
			(layer "B.Fab")
		)
		(fp_line
			(start 0.2794 0.9906)
			(end -0.2794 0.9906)
			(stroke
				(width 0.1)
				(type default)
			)
			(layer "B.Fab")
		)
		(fp_line
			(start -0.2794 -0.1016)
			(end 0.2794 -0.1016)
			(stroke
				(width 0.1)
				(type default)
			)
			(layer "B.Fab")
		)
		(fp_line
			(start 0.2794 -0.1016)
			(end 0.2794 0.9906)
			(stroke
				(width 0.1)
				(type default)
			)
			(layer "B.Fab")
		)
		(pad "1" smd rect
			(at 0 0 90)
			(size 0.508 0.508)
			(layers "B.Cu" "B.Mask" "B.Paste")
			(net "FP_NMI_BTN_OUT_R_N")
		)
		(pad "2" smd rect
			(at 0 0.889 90)
			(size 0.508 0.508)
			(layers "B.Cu" "B.Mask" "B.Paste")
			(net "FP_NMI_BTN_OUT_N")
		)
		(zone
			(layer "B.Cu")
			(hatch none 0.5)
			(connect_pads
				(clearance 0)
			)
			(min_thickness 0.25)
			(keepout
				(tracks not_allowed)
				(vias allowed)
				(pads allowed)
				(copperpour not_allowed)
				(footprints allowed)
			)
			(placement
				(enabled no)
				(sheetname "")
			)
			(fill
				(thermal_gap 0.5)
				(thermal_bridge_width 0.5)
				(island_removal_mode 0)
			)
			(polygon
				(pts
					(xy 411.156658 -11.623802) (xy 411.156658 -12.131802) (xy 411.537658 -12.131802) (xy 411.537658 -11.623802)
				)
			)
		)
		(zone
			(layer "B.Cu")
			(hatch none 0.5)
			(connect_pads
				(clearance 0)
			)
			(min_thickness 0.25)
			(keepout
				(tracks allowed)
				(vias not_allowed)
				(pads allowed)
				(copperpour not_allowed)
				(footprints allowed)
			)
			(placement
				(enabled no)
				(sheetname "")
			)
			(fill
				(thermal_gap 0.5)
				(thermal_bridge_width 0.5)
				(island_removal_mode 0)
			)
			(polygon
				(pts
					(xy 411.537658 -11.623802) (xy 411.537658 -12.131802) (xy 411.156658 -12.131802) (xy 411.156658 -11.623802)
				)
			)
		)
	)
	(footprint ""
		(layer "B.Cu")
		(at 265.864086 -77.82814)
		(property "Reference" "C5P23"
			(at 0 0 0)
			(layer "B.SilkS")
			(hide yes)
			(effects
				(font
					(size 1.27 1.27)
				)
				(justify mirror)
			)
		)
		(property "Value" ""
			(at 0 0 0)
			(layer "B.Fab")
			(effects
				(font
					(size 1.27 1.27)
				)
				(justify mirror)
			)
		)
		(duplicate_pad_numbers_are_jumpers no)
		(fp_poly
			(pts
				(xy 0.7239 -0.2159) (xy -0.7239 -0.2159) (xy -0.7239 1.9939) (xy 0.7239 1.9939)
			)
			(stroke
				(width 0)
				(type default)
			)
			(fill no)
			(layer "B.CrtYd")
		)
		(fp_line
			(start -0.7239 -0.2159)
			(end 0.7239 -0.2159)
			(stroke
				(width 0.1)
				(type default)
			)
			(layer "B.Fab")
		)
		(fp_line
			(start -0.7239 1.9939)
			(end -0.7239 -0.2159)
			(stroke
				(width 0.1)
				(type default)
			)
			(layer "B.Fab")
		)
		(fp_line
			(start 0.7239 -0.2159)
			(end 0.7239 1.9939)
			(stroke
				(width 0.1)
				(type default)
			)
			(layer "B.Fab")
		)
		(fp_line
			(start 0.7239 1.9939)
			(end -0.7239 1.9939)
			(stroke
				(width 0.1)
				(type default)
			)
			(layer "B.Fab")
		)
		(pad "1" smd rect
			(at 0 0 180)
			(size 1.27 1.016)
			(layers "B.Cu" "B.Mask" "B.Paste")
			(net "PVCCIN_CPU0")
		)
		(pad "2" smd rect
			(at 0 1.778 180)
			(size 1.27 1.016)
			(layers "B.Cu" "B.Mask" "B.Paste")
			(net "GND")
		)
		(zone
			(layer "B.Cu")
			(hatch none 0.5)
			(connect_pads
				(clearance 0)
			)
			(min_thickness 0.25)
			(keepout
				(tracks not_allowed)
				(vias allowed)
				(pads allowed)
				(copperpour not_allowed)
				(footprints allowed)
			)
			(placement
				(enabled no)
				(sheetname "")
			)
			(fill
				(thermal_gap 0.5)
				(thermal_bridge_width 0.5)
				(island_removal_mode 0)
			)
			(polygon
				(pts
					(xy 266.499086 -77.32014) (xy 265.229086 -77.32014) (xy 265.229086 -76.55814) (xy 266.499086 -76.55814)
				)
			)
		)
	)
)
